# T6G (Grand Teton) — schematic netlist excerpt (pin names and nets, part order shuffled) for the footprints in the layout excerpt that follows; sources: Cadence DE-HDL packaged netlist, KiCad conversion of 04192023_DAF0TMB3IC0_F0TG_MB_C_brd_V02_OCP.brd

PR531  Q_RES  0 5% CHIP  pkg 0402LF  page 193 : A = NC_PVDDCR_CPU0_P0_IMON7 ; B = GND
C2245  Q_CAP  22UF 4V 20% X6S  pkg C0402  page 69 : A = PVDDCR_CPU1_P0 ; B = GND
PC65  Q_CAP  22UF 4V 20% X6S  pkg C0805  page 226 : A = PVDD18_S5_P1 ; B = GND

(kicad_pcb
	(version 20260206)
	(generator "pcbnew")
	(generator_version "10.0")
	(general
		(thickness 1.6)
		(legacy_teardrops no)
	)
	(paper "A4")
	(title_block
		(title "04192023_DAF0TMB3IC0_F0TG_MB_C_brd_V02_OCP.brd")
		(comment 1 "Grand Teton / footprints 6113-6115 of 8354")
	)
	(layers
		(0 "F.Cu" signal "TOP")
		(4 "In1.Cu" signal "GND")
		(6 "In2.Cu" signal "IN1")
		(8 "In3.Cu" signal "GND1")
		(10 "In4.Cu" signal "IN2")
		(12 "In5.Cu" signal "GND2")
		(14 "In6.Cu" signal "IN3")
		(16 "In7.Cu" signal "GND3")
		(18 "In8.Cu" signal "VCC")
		(20 "In9.Cu" signal "VCC1")
		(22 "In10.Cu" signal "GND4")
		(24 "In11.Cu" signal "IN4")
		(26 "In12.Cu" signal "GND5")
		(28 "In13.Cu" signal "IN5")
		(30 "In14.Cu" signal "GND6")
		(32 "In15.Cu" signal "IN6")
		(34 "In16.Cu" signal "GND7")
		(2 "B.Cu" signal "BOTTOM")
		(9 "F.Adhes" user "F.Adhesive")
		(11 "B.Adhes" user "B.Adhesive")
		(13 "F.Paste" user "Package Geometry/Pastemask Top")
		(15 "B.Paste" user "Package Geometry/Pastemask Bottom")
		(5 "F.SilkS" user "Ref Des/Silkscreen Top")
		(7 "B.SilkS" user "Ref Des/Silkscreen Bottom")
		(1 "F.Mask" user "Board Geometry/Soldermask Top")
		(3 "B.Mask" user "Board Geometry/Soldermask Bottom")
		(17 "Dwgs.User" user "User.Drawings")
		(19 "Cmts.User" user "User.Comments")
		(21 "Eco1.User" user "User.Eco1")
		(23 "Eco2.User" user "User.Eco2")
		(25 "Edge.Cuts" user "Board Geometry/Outline")
		(27 "Margin" user)
		(31 "F.CrtYd" user "Package Geometry/Place Bound Top")
		(29 "B.CrtYd" user "Package Geometry/Place Bound Bottom")
		(35 "F.Fab" user "Ref Des/Assembly Top")
		(33 "B.Fab" user "Ref Des/Assembly Bottom")
	)
	(footprint ""
		(layer "B.Cu")
		(at 371.805454 -268.41831)
		(property "Reference" "C2245"
			(at 0 0 0)
			(layer "B.SilkS")
			(hide yes)
			(effects
				(font
					(size 1.27 1.27)
				)
				(justify mirror)
			)
		)
		(property "Value" ""
			(at 0 0 0)
			(layer "B.Fab")
			(effects
				(font
					(size 1.27 1.27)
				)
				(justify mirror)
			)
		)
		(duplicate_pad_numbers_are_jumpers no)
		(fp_line
			(start -0.7874 -0.4064)
			(end -0.7874 0.4064)
			(stroke
				(width 0.1524)
				(type default)
			)
			(layer "B.SilkS")
		)
		(fp_line
			(start -0.7874 0.4064)
			(end 0.7874 0.4064)
			(stroke
				(width 0.1524)
				(type default)
			)
			(layer "B.SilkS")
		)
		(fp_line
			(start 0.7874 -0.4064)
			(end -0.7874 -0.4064)
			(stroke
				(width 0.1524)
				(type default)
			)
			(layer "B.SilkS")
		)
		(fp_line
			(start 0.7874 0.4064)
			(end 0.7874 -0.4064)
			(stroke
				(width 0.1524)
				(type default)
			)
			(layer "B.SilkS")
		)
		(fp_line
			(start -0.67945 -0.3048)
			(end -0.67945 0.3048)
			(stroke
				(width 0.1)
				(type default)
			)
			(layer "B.Fab")
		)
		(fp_line
			(start -0.67945 0.3048)
			(end -0.120396 0.3048)
			(stroke
				(width 0.1)
				(type default)
			)
			(layer "B.Fab")
		)
		(fp_line
			(start -0.12065 -0.3048)
			(end -0.67945 -0.3048)
			(stroke
				(width 0.1)
				(type default)
			)
			(layer "B.Fab")
		)
		(fp_line
			(start -0.12065 -0.2794)
			(end -0.12065 -0.3048)
			(stroke
				(width 0.1)
				(type default)
			)
			(layer "B.Fab")
		)
		(fp_line
			(start -0.120396 0.2794)
			(end 0.12065 0.2794)
			(stroke
				(width 0.1)
				(type default)
			)
			(layer "B.Fab")
		)
		(fp_line
			(start -0.120396 0.3048)
			(end -0.120396 0.2794)
			(stroke
				(width 0.1)
				(type default)
			)
			(layer "B.Fab")
		)
		(fp_line
			(start 0.12065 -0.305054)
			(end 0.12065 -0.2794)
			(stroke
				(width 0.1)
				(type default)
			)
			(layer "B.Fab")
		)
		(fp_line
			(start 0.12065 -0.2794)
			(end -0.12065 -0.2794)
			(stroke
				(width 0.1)
				(type default)
			)
			(layer "B.Fab")
		)
		(fp_line
			(start 0.12065 0.2794)
			(end 0.12065 0.3048)
			(stroke
				(width 0.1)
				(type default)
			)
			(layer "B.Fab")
		)
		(fp_line
			(start 0.12065 0.3048)
			(end 0.67945 0.3048)
			(stroke
				(width 0.1)
				(type default)
			)
			(layer "B.Fab")
		)
		(fp_line
			(start 0.67945 -0.305054)
			(end 0.12065 -0.305054)
			(stroke
				(width 0.1)
				(type default)
			)
			(layer "B.Fab")
		)
		(fp_line
			(start 0.67945 0.3048)
			(end 0.67945 -0.305054)
			(stroke
				(width 0.1)
				(type default)
			)
			(layer "B.Fab")
		)
		(pad "1" smd circle
			(at 0.40005 0 180)
			(size 0 0)
			(layers "B.Cu" "B.Mask" "B.Paste")
			(net "PVDDCR_CPU1_P0")
		)
		(pad "2" smd circle
			(at -0.40005 0 180)
			(size 0 0)
			(layers "B.Cu" "B.Mask" "B.Paste")
			(net "GND")
		)
	)
	(footprint ""
		(layer "B.Cu")
		(at 379.613922 -148.30171 -90)
		(property "Reference" "PR531"
			(at 0 0 90)
			(layer "B.SilkS")
			(hide yes)
			(effects
				(font
					(size 1.27 1.27)
				)
				(justify mirror)
			)
		)
		(property "Value" ""
			(at 0 0 90)
			(layer "B.Fab")
			(effects
				(font
					(size 1.27 1.27)
				)
				(justify mirror)
			)
		)
		(duplicate_pad_numbers_are_jumpers no)
		(fp_line
			(start -0.7874 0.4064)
			(end 0.7874 0.4064)
			(stroke
				(width 0.1524)
				(type default)
			)
			(layer "B.SilkS")
		)
		(fp_line
			(start 0.7874 0.4064)
			(end 0.7874 -0.4064)
			(stroke
				(width 0.1524)
				(type default)
			)
			(layer "B.SilkS")
		)
		(fp_line
			(start -0.7874 -0.4064)
			(end -0.7874 0.4064)
			(stroke
				(width 0.1524)
				(type default)
			)
			(layer "B.SilkS")
		)
		(fp_line
			(start 0.7874 -0.4064)
			(end -0.7874 -0.4064)
			(stroke
				(width 0.1524)
				(type default)
			)
			(layer "B.SilkS")
		)
		(fp_line
			(start -0.67945 0.3048)
			(end -0.120396 0.3048)
			(stroke
				(width 0.1)
				(type default)
			)
			(layer "B.Fab")
		)
		(fp_line
			(start -0.120396 0.3048)
			(end -0.120396 0.2794)
			(stroke
				(width 0.1)
				(type default)
			)
			(layer "B.Fab")
		)
		(fp_line
			(start 0.12065 0.3048)
			(end 0.67945 0.3048)
			(stroke
				(width 0.1)
				(type default)
			)
			(layer "B.Fab")
		)
		(fp_line
			(start 0.67945 0.3048)
			(end 0.67945 -0.305054)
			(stroke
				(width 0.1)
				(type default)
			)
			(layer "B.Fab")
		)
		(fp_line
			(start -0.120396 0.2794)
			(end 0.12065 0.2794)
			(stroke
				(width 0.1)
				(type default)
			)
			(layer "B.Fab")
		)
		(fp_line
			(start 0.12065 0.2794)
			(end 0.12065 0.3048)
			(stroke
				(width 0.1)
				(type default)
			)
			(layer "B.Fab")
		)
		(fp_line
			(start -0.12065 -0.2794)
			(end -0.12065 -0.3048)
			(stroke
				(width 0.1)
				(type default)
			)
			(layer "B.Fab")
		)
		(fp_line
			(start 0.12065 -0.2794)
			(end -0.12065 -0.2794)
			(stroke
				(width 0.1)
				(type default)
			)
			(layer "B.Fab")
		)
		(fp_line
			(start -0.67945 -0.3048)
			(end -0.67945 0.3048)
			(stroke
				(width 0.1)
				(type default)
			)
			(layer "B.Fab")
		)
		(fp_line
			(start -0.12065 -0.3048)
			(end -0.67945 -0.3048)
			(stroke
				(width 0.1)
				(type default)
			)
			(layer "B.Fab")
		)
		(fp_line
			(start 0.12065 -0.305054)
			(end 0.12065 -0.2794)
			(stroke
				(width 0.1)
				(type default)
			)
			(layer "B.Fab")
		)
		(fp_line
			(start 0.67945 -0.305054)
			(end 0.12065 -0.305054)
			(stroke
				(width 0.1)
				(type default)
			)
			(layer "B.Fab")
		)
		(pad "1" smd circle
			(at 0.40005 0 90)
			(size 0 0)
			(layers "B.Cu" "B.Mask" "B.Paste")
			(net "NC_PVDDCR_CPU0_P0_IMON7")
		)
		(pad "2" smd circle
			(at -0.40005 0 90)
			(size 0 0)
			(layers "B.Cu" "B.Mask" "B.Paste")
			(net "GND")
		)
	)
	(footprint ""
		(layer "B.Cu")
		(at 58.656982 -153.821892 180)
		(property "Reference" "PC65"
			(at 0 0 0)
			(layer "B.SilkS")
			(hide yes)
			(effects
				(font
					(size 1.27 1.27)
				)
				(justify mirror)
			)
		)
		(property "Value" ""
			(at 0 0 0)
			(layer "B.Fab")
			(effects
				(font
					(size 1.27 1.27)
				)
				(justify mirror)
			)
		)
		(duplicate_pad_numbers_are_jumpers no)
		(fp_line
			(start 1.524 0.762)
			(end 1.524 -0.762)
			(stroke
				(width 0.1524)
				(type default)
			)
			(layer "B.SilkS")
		)
		(fp_line
			(start 1.524 -0.762)
			(end -1.524 -0.762)
			(stroke
				(width 0.1524)
				(type default)
			)
			(layer "B.SilkS")
		)
		(fp_line
			(start -1.524 0.762)
			(end 1.524 0.762)
			(stroke
				(width 0.1524)
				(type default)
			)
			(layer "B.SilkS")
		)
		(fp_line
			(start -1.524 -0.762)
			(end -1.524 0.762)
			(stroke
				(width 0.1524)
				(type default)
			)
			(layer "B.SilkS")
		)
		(fp_line
			(start 1.1049 0.724916)
			(end -1.1049 0.724916)
			(stroke
				(width 0.1)
				(type default)
			)
			(layer "B.Fab")
		)
		(fp_line
			(start 1.1049 -0.724916)
			(end 1.1049 0.724916)
			(stroke
				(width 0.1)
				(type default)
			)
			(layer "B.Fab")
		)
		(fp_line
			(start -1.1049 0.724916)
			(end -1.1049 -0.724916)
			(stroke
				(width 0.1)
				(type default)
			)
			(layer "B.Fab")
		)
		(fp_line
			(start -1.1049 -0.724916)
			(end 1.1049 -0.724916)
			(stroke
				(width 0.1)
				(type default)
			)
			(layer "B.Fab")
		)
		(pad "1" smd rect
			(at 0.889 0 180)
			(size 1.016 1.27)
			(layers "B.Cu" "B.Mask" "B.Paste")
			(net "PVDD18_S5_P1")
		)
		(pad "2" smd rect
			(at -0.889 0 180)
			(size 1.016 1.27)
			(layers "B.Cu" "B.Mask" "B.Paste")
			(net "GND")
		)
	)
)
